# T6G (Grand Teton) — schematic netlist excerpt (pin names and nets, part order shuffled) for the footprints in the layout excerpt that follows; sources: Cadence DE-HDL packaged netlist, KiCad conversion of 04192023_DAF0TMB3IC0_F0TG_MB_C_brd_V02_OCP.brd

R3997  Q_RES  0 5% CHIP  pkg 0402LF  page 152 : A = P12V_SCM_UV_R ; B = P12V_SCM_UV
R601  Q_RES  1K 1% CHIP  pkg 0402LF  page 77 : A = PVDD18_S5_P0 ; B = SPI_CPU0_CS1_N

(kicad_pcb
	(version 20260206)
	(generator "pcbnew")
	(generator_version "10.0")
	(general
		(thickness 1.6)
		(legacy_teardrops no)
	)
	(paper "A4")
	(title_block
		(title "04192023_DAF0TMB3IC0_F0TG_MB_C_brd_V02_OCP.brd")
		(comment 1 "Grand Teton / footprints 4533-4534 of 8354")
	)
	(layers
		(0 "F.Cu" signal "TOP")
		(4 "In1.Cu" signal "GND")
		(6 "In2.Cu" signal "IN1")
		(8 "In3.Cu" signal "GND1")
		(10 "In4.Cu" signal "IN2")
		(12 "In5.Cu" signal "GND2")
		(14 "In6.Cu" signal "IN3")
		(16 "In7.Cu" signal "GND3")
		(18 "In8.Cu" signal "VCC")
		(20 "In9.Cu" signal "VCC1")
		(22 "In10.Cu" signal "GND4")
		(24 "In11.Cu" signal "IN4")
		(26 "In12.Cu" signal "GND5")
		(28 "In13.Cu" signal "IN5")
		(30 "In14.Cu" signal "GND6")
		(32 "In15.Cu" signal "IN6")
		(34 "In16.Cu" signal "GND7")
		(2 "B.Cu" signal "BOTTOM")
		(9 "F.Adhes" user "F.Adhesive")
		(11 "B.Adhes" user "B.Adhesive")
		(13 "F.Paste" user "Package Geometry/Pastemask Top")
		(15 "B.Paste" user "Package Geometry/Pastemask Bottom")
		(5 "F.SilkS" user "Ref Des/Silkscreen Top")
		(7 "B.SilkS" user "Ref Des/Silkscreen Bottom")
		(1 "F.Mask" user "Board Geometry/Soldermask Top")
		(3 "B.Mask" user "Board Geometry/Soldermask Bottom")
		(17 "Dwgs.User" user "User.Drawings")
		(19 "Cmts.User" user "User.Comments")
		(21 "Eco1.User" user "User.Eco1")
		(23 "Eco2.User" user "User.Eco2")
		(25 "Edge.Cuts" user "Board Geometry/Outline")
		(27 "Margin" user)
		(31 "F.CrtYd" user "Package Geometry/Place Bound Top")
		(29 "B.CrtYd" user "Package Geometry/Place Bound Bottom")
		(35 "F.Fab" user "Ref Des/Assembly Top")
		(33 "B.Fab" user "Ref Des/Assembly Bottom")
	)
	(footprint ""
		(layer "F.Cu")
		(at 190.43269 -41.011602 180)
		(property "Reference" "R3997"
			(at 0 0 180)
			(layer "F.SilkS")
			(hide yes)
			(effects
				(font
					(size 1.27 1.27)
				)
			)
		)
		(property "Value" ""
			(at 0 0 180)
			(layer "F.Fab")
			(effects
				(font
					(size 1.27 1.27)
				)
			)
		)
		(duplicate_pad_numbers_are_jumpers no)
		(fp_line
			(start 0.7874 0.4064)
			(end -0.7874 0.4064)
			(stroke
				(width 0.1524)
				(type default)
			)
			(layer "F.SilkS")
		)
		(fp_line
			(start 0.7874 -0.4064)
			(end 0.7874 0.4064)
			(stroke
				(width 0.1524)
				(type default)
			)
			(layer "F.SilkS")
		)
		(fp_line
			(start -0.7874 0.4064)
			(end -0.7874 -0.4064)
			(stroke
				(width 0.1524)
				(type default)
			)
			(layer "F.SilkS")
		)
		(fp_line
			(start -0.7874 -0.4064)
			(end 0.7874 -0.4064)
			(stroke
				(width 0.1524)
				(type default)
			)
			(layer "F.SilkS")
		)
		(fp_line
			(start 0.67945 0.3048)
			(end 0.120396 0.3048)
			(stroke
				(width 0.1)
				(type default)
			)
			(layer "F.Fab")
		)
		(fp_line
			(start 0.67945 -0.3048)
			(end 0.67945 0.3048)
			(stroke
				(width 0.1)
				(type default)
			)
			(layer "F.Fab")
		)
		(fp_line
			(start 0.12065 -0.2794)
			(end 0.12065 -0.3048)
			(stroke
				(width 0.1)
				(type default)
			)
			(layer "F.Fab")
		)
		(fp_line
			(start 0.12065 -0.3048)
			(end 0.67945 -0.3048)
			(stroke
				(width 0.1)
				(type default)
			)
			(layer "F.Fab")
		)
		(fp_line
			(start 0.120396 0.3048)
			(end 0.120396 0.2794)
			(stroke
				(width 0.1)
				(type default)
			)
			(layer "F.Fab")
		)
		(fp_line
			(start 0.120396 0.2794)
			(end -0.12065 0.2794)
			(stroke
				(width 0.1)
				(type default)
			)
			(layer "F.Fab")
		)
		(fp_line
			(start -0.12065 0.3048)
			(end -0.67945 0.3048)
			(stroke
				(width 0.1)
				(type default)
			)
			(layer "F.Fab")
		)
		(fp_line
			(start -0.12065 0.2794)
			(end -0.12065 0.3048)
			(stroke
				(width 0.1)
				(type default)
			)
			(layer "F.Fab")
		)
		(fp_line
			(start -0.12065 -0.2794)
			(end 0.12065 -0.2794)
			(stroke
				(width 0.1)
				(type default)
			)
			(layer "F.Fab")
		)
		(fp_line
			(start -0.12065 -0.305054)
			(end -0.12065 -0.2794)
			(stroke
				(width 0.1)
				(type default)
			)
			(layer "F.Fab")
		)
		(fp_line
			(start -0.67945 0.3048)
			(end -0.67945 -0.305054)
			(stroke
				(width 0.1)
				(type default)
			)
			(layer "F.Fab")
		)
		(fp_line
			(start -0.67945 -0.305054)
			(end -0.12065 -0.305054)
			(stroke
				(width 0.1)
				(type default)
			)
			(layer "F.Fab")
		)
		(pad "1" smd circle
			(at -0.40005 0 180)
			(size 0 0)
			(layers "F.Cu" "F.Mask" "F.Paste")
			(net "P12V_SCM_UV_R")
		)
		(pad "2" smd circle
			(at 0.40005 0 180)
			(size 0 0)
			(layers "F.Cu" "F.Mask" "F.Paste")
			(net "P12V_SCM_UV")
		)
	)
	(footprint ""
		(layer "F.Cu")
		(at 264.478516 -133.622796 180)
		(property "Reference" "R601"
			(at 0 0 180)
			(layer "F.SilkS")
			(hide yes)
			(effects
				(font
					(size 1.27 1.27)
				)
			)
		)
		(property "Value" ""
			(at 0 0 180)
			(layer "F.Fab")
			(effects
				(font
					(size 1.27 1.27)
				)
			)
		)
		(duplicate_pad_numbers_are_jumpers no)
		(fp_line
			(start 0.7874 0.4064)
			(end -0.7874 0.4064)
			(stroke
				(width 0.1524)
				(type default)
			)
			(layer "F.SilkS")
		)
		(fp_line
			(start 0.7874 -0.4064)
			(end 0.7874 0.4064)
			(stroke
				(width 0.1524)
				(type default)
			)
			(layer "F.SilkS")
		)
		(fp_line
			(start -0.7874 0.4064)
			(end -0.7874 -0.4064)
			(stroke
				(width 0.1524)
				(type default)
			)
			(layer "F.SilkS")
		)
		(fp_line
			(start -0.7874 -0.4064)
			(end 0.7874 -0.4064)
			(stroke
				(width 0.1524)
				(type default)
			)
			(layer "F.SilkS")
		)
		(fp_line
			(start 0.67945 0.3048)
			(end 0.120396 0.3048)
			(stroke
				(width 0.1)
				(type default)
			)
			(layer "F.Fab")
		)
		(fp_line
			(start 0.67945 -0.3048)
			(end 0.67945 0.3048)
			(stroke
				(width 0.1)
				(type default)
			)
			(layer "F.Fab")
		)
		(fp_line
			(start 0.12065 -0.2794)
			(end 0.12065 -0.3048)
			(stroke
				(width 0.1)
				(type default)
			)
			(layer "F.Fab")
		)
		(fp_line
			(start 0.12065 -0.3048)
			(end 0.67945 -0.3048)
			(stroke
				(width 0.1)
				(type default)
			)
			(layer "F.Fab")
		)
		(fp_line
			(start 0.120396 0.3048)
			(end 0.120396 0.2794)
			(stroke
				(width 0.1)
				(type default)
			)
			(layer "F.Fab")
		)
		(fp_line
			(start 0.120396 0.2794)
			(end -0.12065 0.2794)
			(stroke
				(width 0.1)
				(type default)
			)
			(layer "F.Fab")
		)
		(fp_line
			(start -0.12065 0.3048)
			(end -0.67945 0.3048)
			(stroke
				(width 0.1)
				(type default)
			)
			(layer "F.Fab")
		)
		(fp_line
			(start -0.12065 0.2794)
			(end -0.12065 0.3048)
			(stroke
				(width 0.1)
				(type default)
			)
			(layer "F.Fab")
		)
		(fp_line
			(start -0.12065 -0.2794)
			(end 0.12065 -0.2794)
			(stroke
				(width 0.1)
				(type default)
			)
			(layer "F.Fab")
		)
		(fp_line
			(start -0.12065 -0.305054)
			(end -0.12065 -0.2794)
			(stroke
				(width 0.1)
				(type default)
			)
			(layer "F.Fab")
		)
		(fp_line
			(start -0.67945 0.3048)
			(end -0.67945 -0.305054)
			(stroke
				(width 0.1)
				(type default)
			)
			(layer "F.Fab")
		)
		(fp_line
			(start -0.67945 -0.305054)
			(end -0.12065 -0.305054)
			(stroke
				(width 0.1)
				(type default)
			)
			(layer "F.Fab")
		)
		(pad "1" smd circle
			(at -0.40005 0 180)
			(size 0 0)
			(layers "F.Cu" "F.Mask" "F.Paste")
			(net "PVDD18_S5_P0")
		)
		(pad "2" smd circle
			(at 0.40005 0 180)
			(size 0 0)
			(layers "F.Cu" "F.Mask" "F.Paste")
			(net "SPI_CPU0_CS1_N")
		)
	)
)
